(kicad_pcb
	(version 20260206)
	(generator "pcbnew")
	(generator_version "10.0")
	(general
		(thickness 1.6)
		(legacy_teardrops no)
	)
	(paper "A4")
	(title_block
		(title "01162023_DA0F0TEBIF0_F0T_Expander_BD_F_brd_V02_OCP.brd")
		(comment 1 "Grand Teton / footprints 7540-7547 of 9728")
	)
	(layers
		(0 "F.Cu" signal "TOP")
		(4 "In1.Cu" signal "GND")
		(6 "In2.Cu" signal "VCC")
		(8 "In3.Cu" signal "VCC1")
		(10 "In4.Cu" signal "GND1")
		(12 "In5.Cu" signal "IN1")
		(14 "In6.Cu" signal "GND2")
		(16 "In7.Cu" signal "IN2")
		(18 "In8.Cu" signal "GND3")
		(20 "In9.Cu" signal "IN3")
		(22 "In10.Cu" signal "GND4")
		(24 "In11.Cu" signal "IN4")
		(26 "In12.Cu" signal "GND5")
		(28 "In13.Cu" signal "IN5")
		(30 "In14.Cu" signal "GND6")
		(32 "In15.Cu" signal "IN6")
		(34 "In16.Cu" signal "GND7")
		(2 "B.Cu" signal "BOTTOM")
		(9 "F.Adhes" user "F.Adhesive")
		(11 "B.Adhes" user "B.Adhesive")
		(13 "F.Paste" user "Package Geometry/Pastemask Top")
		(15 "B.Paste" user "Package Geometry/Pastemask Bottom")
		(5 "F.SilkS" user "Ref Des/Silkscreen Top")
		(7 "B.SilkS" user "Ref Des/Silkscreen Bottom")
		(1 "F.Mask" user "Board Geometry/Soldermask Top")
		(3 "B.Mask" user "Board Geometry/Soldermask Bottom")
		(17 "Dwgs.User" user "User.Drawings")
		(19 "Cmts.User" user "User.Comments")
		(21 "Eco1.User" user "User.Eco1")
		(23 "Eco2.User" user "User.Eco2")
		(25 "Edge.Cuts" user "Board Geometry/Outline")
		(27 "Margin" user)
		(31 "F.CrtYd" user "Package Geometry/Place Bound Top")
		(29 "B.CrtYd" user "Package Geometry/Place Bound Bottom")
		(35 "F.Fab" user "Ref Des/Assembly Top")
		(33 "B.Fab" user "Ref Des/Assembly Bottom")
	)
	(footprint ""
		(layer "B.Cu")
		(at 225.19894 -193.759582 90)
		(property "Reference" "R466"
			(at 0 0 90)
			(layer "B.SilkS")
			(hide yes)
			(effects
				(font
					(size 1.27 1.27)
				)
				(justify mirror)
			)
		)
		(property "Value" ""
			(at 0 0 90)
			(layer "B.Fab")
			(effects
				(font
					(size 1.27 1.27)
				)
				(justify mirror)
			)
		)
		(duplicate_pad_numbers_are_jumpers no)
		(fp_line
			(start 0.7874 -0.4064)
			(end -0.7874 -0.4064)
			(stroke
				(width 0.1524)
				(type default)
			)
			(layer "B.SilkS")
		)
		(fp_line
			(start -0.7874 -0.4064)
			(end -0.7874 0.4064)
			(stroke
				(width 0.1524)
				(type default)
			)
			(layer "B.SilkS")
		)
		(fp_line
			(start 0.7874 0.4064)
			(end 0.7874 -0.4064)
			(stroke
				(width 0.1524)
				(type default)
			)
			(layer "B.SilkS")
		)
		(fp_line
			(start -0.7874 0.4064)
			(end 0.7874 0.4064)
			(stroke
				(width 0.1524)
				(type default)
			)
			(layer "B.SilkS")
		)
		(fp_line
			(start 0.67945 -0.305054)
			(end 0.12065 -0.305054)
			(stroke
				(width 0.1)
				(type default)
			)
			(layer "B.Fab")
		)
		(fp_line
			(start 0.12065 -0.305054)
			(end 0.12065 -0.2794)
			(stroke
				(width 0.1)
				(type default)
			)
			(layer "B.Fab")
		)
		(fp_line
			(start -0.12065 -0.3048)
			(end -0.67945 -0.3048)
			(stroke
				(width 0.1)
				(type default)
			)
			(layer "B.Fab")
		)
		(fp_line
			(start -0.67945 -0.3048)
			(end -0.67945 0.3048)
			(stroke
				(width 0.1)
				(type default)
			)
			(layer "B.Fab")
		)
		(fp_line
			(start 0.12065 -0.2794)
			(end -0.12065 -0.2794)
			(stroke
				(width 0.1)
				(type default)
			)
			(layer "B.Fab")
		)
		(fp_line
			(start -0.12065 -0.2794)
			(end -0.12065 -0.3048)
			(stroke
				(width 0.1)
				(type default)
			)
			(layer "B.Fab")
		)
		(fp_line
			(start 0.12065 0.2794)
			(end 0.12065 0.3048)
			(stroke
				(width 0.1)
				(type default)
			)
			(layer "B.Fab")
		)
		(fp_line
			(start -0.120396 0.2794)
			(end 0.12065 0.2794)
			(stroke
				(width 0.1)
				(type default)
			)
			(layer "B.Fab")
		)
		(fp_line
			(start 0.67945 0.3048)
			(end 0.67945 -0.305054)
			(stroke
				(width 0.1)
				(type default)
			)
			(layer "B.Fab")
		)
		(fp_line
			(start 0.12065 0.3048)
			(end 0.67945 0.3048)
			(stroke
				(width 0.1)
				(type default)
			)
			(layer "B.Fab")
		)
		(fp_line
			(start -0.120396 0.3048)
			(end -0.120396 0.2794)
			(stroke
				(width 0.1)
				(type default)
			)
			(layer "B.Fab")
		)
		(fp_line
			(start -0.67945 0.3048)
			(end -0.120396 0.3048)
			(stroke
				(width 0.1)
				(type default)
			)
			(layer "B.Fab")
		)
		(pad "1" smd circle
			(at 0.40005 0 270)
			(size 0 0)
			(layers "B.Cu" "B.Mask" "B.Paste")
			(net "SPI_BIC1_CLK_R1")
		)
		(pad "2" smd circle
			(at -0.40005 0 270)
			(size 0 0)
			(layers "B.Cu" "B.Mask" "B.Paste")
			(net "SPI_BIC1_CLK_R2")
		)
	)
	(footprint ""
		(layer "B.Cu")
		(at 276.649688 -300.174914)
		(property "Reference" "C3356"
			(at 0 0 0)
			(layer "B.SilkS")
			(hide yes)
			(effects
				(font
					(size 1.27 1.27)
				)
				(justify mirror)
			)
		)
		(property "Value" ""
			(at 0 0 0)
			(layer "B.Fab")
			(effects
				(font
					(size 1.27 1.27)
				)
				(justify mirror)
			)
		)
		(duplicate_pad_numbers_are_jumpers no)
		(fp_line
			(start -0.299974 -0.150114)
			(end -0.299974 0.150114)
			(stroke
				(width 0.1)
				(type default)
			)
			(layer "B.Fab")
		)
		(fp_line
			(start -0.299974 0.150114)
			(end 0.299974 0.150114)
			(stroke
				(width 0.1)
				(type default)
			)
			(layer "B.Fab")
		)
		(fp_line
			(start 0.299974 -0.150114)
			(end -0.299974 -0.150114)
			(stroke
				(width 0.1)
				(type default)
			)
			(layer "B.Fab")
		)
		(fp_line
			(start 0.299974 0.150114)
			(end 0.299974 -0.150114)
			(stroke
				(width 0.1)
				(type default)
			)
			(layer "B.Fab")
		)
		(pad "1" smd rect
			(at 0.2667 0 180)
			(size 0.3048 0.381)
			(layers "B.Cu" "B.Mask" "B.Paste")
			(net "P1V8_VDDA_PEX2")
		)
		(pad "2" smd rect
			(at -0.2667 0 180)
			(size 0.3048 0.381)
			(layers "B.Cu" "B.Mask" "B.Paste")
			(net "GND")
		)
	)
	(footprint ""
		(layer "B.Cu")
		(at 140.183108 -220.932756 90)
		(property "Reference" "R3461"
			(at 0 0 90)
			(layer "B.SilkS")
			(hide yes)
			(effects
				(font
					(size 1.27 1.27)
				)
				(justify mirror)
			)
		)
		(property "Value" ""
			(at 0 0 90)
			(layer "B.Fab")
			(effects
				(font
					(size 1.27 1.27)
				)
				(justify mirror)
			)
		)
		(duplicate_pad_numbers_are_jumpers no)
		(fp_line
			(start 0.7874 -0.4064)
			(end -0.7874 -0.4064)
			(stroke
				(width 0.1524)
				(type default)
			)
			(layer "B.SilkS")
		)
		(fp_line
			(start -0.7874 -0.4064)
			(end -0.7874 0.4064)
			(stroke
				(width 0.1524)
				(type default)
			)
			(layer "B.SilkS")
		)
		(fp_line
			(start 0.7874 0.4064)
			(end 0.7874 -0.4064)
			(stroke
				(width 0.1524)
				(type default)
			)
			(layer "B.SilkS")
		)
		(fp_line
			(start -0.7874 0.4064)
			(end 0.7874 0.4064)
			(stroke
				(width 0.1524)
				(type default)
			)
			(layer "B.SilkS")
		)
		(fp_line
			(start 0.67945 -0.305054)
			(end 0.12065 -0.305054)
			(stroke
				(width 0.1)
				(type default)
			)
			(layer "B.Fab")
		)
		(fp_line
			(start 0.12065 -0.305054)
			(end 0.12065 -0.2794)
			(stroke
				(width 0.1)
				(type default)
			)
			(layer "B.Fab")
		)
		(fp_line
			(start -0.12065 -0.3048)
			(end -0.67945 -0.3048)
			(stroke
				(width 0.1)
				(type default)
			)
			(layer "B.Fab")
		)
		(fp_line
			(start -0.67945 -0.3048)
			(end -0.67945 0.3048)
			(stroke
				(width 0.1)
				(type default)
			)
			(layer "B.Fab")
		)
		(fp_line
			(start 0.12065 -0.2794)
			(end -0.12065 -0.2794)
			(stroke
				(width 0.1)
				(type default)
			)
			(layer "B.Fab")
		)
		(fp_line
			(start -0.12065 -0.2794)
			(end -0.12065 -0.3048)
			(stroke
				(width 0.1)
				(type default)
			)
			(layer "B.Fab")
		)
		(fp_line
			(start 0.12065 0.2794)
			(end 0.12065 0.3048)
			(stroke
				(width 0.1)
				(type default)
			)
			(layer "B.Fab")
		)
		(fp_line
			(start -0.120396 0.2794)
			(end 0.12065 0.2794)
			(stroke
				(width 0.1)
				(type default)
			)
			(layer "B.Fab")
		)
		(fp_line
			(start 0.67945 0.3048)
			(end 0.67945 -0.305054)
			(stroke
				(width 0.1)
				(type default)
			)
			(layer "B.Fab")
		)
		(fp_line
			(start 0.12065 0.3048)
			(end 0.67945 0.3048)
			(stroke
				(width 0.1)
				(type default)
			)
			(layer "B.Fab")
		)
		(fp_line
			(start -0.120396 0.3048)
			(end -0.120396 0.2794)
			(stroke
				(width 0.1)
				(type default)
			)
			(layer "B.Fab")
		)
		(fp_line
			(start -0.67945 0.3048)
			(end -0.120396 0.3048)
			(stroke
				(width 0.1)
				(type default)
			)
			(layer "B.Fab")
		)
		(pad "1" smd circle
			(at 0.40005 0 270)
			(size 0 0)
			(layers "B.Cu" "B.Mask" "B.Paste")
			(net "SPI_PEX1_SDIO3_R")
		)
		(pad "2" smd circle
			(at -0.40005 0 270)
			(size 0 0)
			(layers "B.Cu" "B.Mask" "B.Paste")
			(net "SPI_PEX1_SDIO3_R1")
		)
	)
	(footprint ""
		(layer "B.Cu")
		(at 404.624794 -286.399732 90)
		(property "Reference" "C3474"
			(at 0 0 90)
			(layer "B.SilkS")
			(hide yes)
			(effects
				(font
					(size 1.27 1.27)
				)
				(justify mirror)
			)
		)
		(property "Value" ""
			(at 0 0 90)
			(layer "B.Fab")
			(effects
				(font
					(size 1.27 1.27)
				)
				(justify mirror)
			)
		)
		(duplicate_pad_numbers_are_jumpers no)
		(fp_line
			(start 0.299974 -0.150114)
			(end -0.299974 -0.150114)
			(stroke
				(width 0.1)
				(type default)
			)
			(layer "B.Fab")
		)
		(fp_line
			(start -0.299974 -0.150114)
			(end -0.299974 0.150114)
			(stroke
				(width 0.1)
				(type default)
			)
			(layer "B.Fab")
		)
		(fp_line
			(start 0.299974 0.150114)
			(end 0.299974 -0.150114)
			(stroke
				(width 0.1)
				(type default)
			)
			(layer "B.Fab")
		)
		(fp_line
			(start -0.299974 0.150114)
			(end 0.299974 0.150114)
			(stroke
				(width 0.1)
				(type default)
			)
			(layer "B.Fab")
		)
		(pad "1" smd rect
			(at 0.2667 0 270)
			(size 0.3048 0.381)
			(layers "B.Cu" "B.Mask" "B.Paste")
			(net "P1V25_SERDES_VDDPLL_PEX3")
		)
		(pad "2" smd rect
			(at -0.2667 0 270)
			(size 0.3048 0.381)
			(layers "B.Cu" "B.Mask" "B.Paste")
			(net "GND")
		)
	)
	(footprint ""
		(layer "B.Cu")
		(at 167.200072 -299.699934 -90)
		(property "Reference" "C1426"
			(at 0 0 90)
			(layer "B.SilkS")
			(hide yes)
			(effects
				(font
					(size 1.27 1.27)
				)
				(justify mirror)
			)
		)
		(property "Value" ""
			(at 0 0 90)
			(layer "B.Fab")
			(effects
				(font
					(size 1.27 1.27)
				)
				(justify mirror)
			)
		)
		(duplicate_pad_numbers_are_jumpers no)
		(fp_line
			(start -0.299974 0.150114)
			(end 0.299974 0.150114)
			(stroke
				(width 0.1)
				(type default)
			)
			(layer "B.Fab")
		)
		(fp_line
			(start 0.299974 0.150114)
			(end 0.299974 -0.150114)
			(stroke
				(width 0.1)
				(type default)
			)
			(layer "B.Fab")
		)
		(fp_line
			(start -0.299974 -0.150114)
			(end -0.299974 0.150114)
			(stroke
				(width 0.1)
				(type default)
			)
			(layer "B.Fab")
		)
		(fp_line
			(start 0.299974 -0.150114)
			(end -0.299974 -0.150114)
			(stroke
				(width 0.1)
				(type default)
			)
			(layer "B.Fab")
		)
		(pad "1" smd rect
			(at 0.2667 0 90)
			(size 0.3048 0.381)
			(layers "B.Cu" "B.Mask" "B.Paste")
			(net "P0V8_SERDES_VDDA_PEX1")
		)
		(pad "2" smd rect
			(at -0.2667 0 90)
			(size 0.3048 0.381)
			(layers "B.Cu" "B.Mask" "B.Paste")
			(net "GND")
		)
	)
	(footprint ""
		(layer "B.Cu")
		(at 352.074988 -321.160394 -90)
		(property "Reference" "R6535"
			(at 0 0 90)
			(layer "B.SilkS")
			(hide yes)
			(effects
				(font
					(size 1.27 1.27)
				)
				(justify mirror)
			)
		)
		(property "Value" ""
			(at 0 0 90)
			(layer "B.Fab")
			(effects
				(font
					(size 1.27 1.27)
				)
				(justify mirror)
			)
		)
		(duplicate_pad_numbers_are_jumpers no)
		(fp_line
			(start -0.7874 0.4064)
			(end 0.7874 0.4064)
			(stroke
				(width 0.1524)
				(type default)
			)
			(layer "B.SilkS")
		)
		(fp_line
			(start 0.7874 0.4064)
			(end 0.7874 -0.4064)
			(stroke
				(width 0.1524)
				(type default)
			)
			(layer "B.SilkS")
		)
		(fp_line
			(start -0.7874 -0.4064)
			(end -0.7874 0.4064)
			(stroke
				(width 0.1524)
				(type default)
			)
			(layer "B.SilkS")
		)
		(fp_line
			(start 0.7874 -0.4064)
			(end -0.7874 -0.4064)
			(stroke
				(width 0.1524)
				(type default)
			)
			(layer "B.SilkS")
		)
		(fp_line
			(start -0.67945 0.3048)
			(end -0.120396 0.3048)
			(stroke
				(width 0.1)
				(type default)
			)
			(layer "B.Fab")
		)
		(fp_line
			(start -0.120396 0.3048)
			(end -0.120396 0.2794)
			(stroke
				(width 0.1)
				(type default)
			)
			(layer "B.Fab")
		)
		(fp_line
			(start 0.12065 0.3048)
			(end 0.67945 0.3048)
			(stroke
				(width 0.1)
				(type default)
			)
			(layer "B.Fab")
		)
		(fp_line
			(start 0.67945 0.3048)
			(end 0.67945 -0.305054)
			(stroke
				(width 0.1)
				(type default)
			)
			(layer "B.Fab")
		)
		(fp_line
			(start -0.120396 0.2794)
			(end 0.12065 0.2794)
			(stroke
				(width 0.1)
				(type default)
			)
			(layer "B.Fab")
		)
		(fp_line
			(start 0.12065 0.2794)
			(end 0.12065 0.3048)
			(stroke
				(width 0.1)
				(type default)
			)
			(layer "B.Fab")
		)
		(fp_line
			(start -0.12065 -0.2794)
			(end -0.12065 -0.3048)
			(stroke
				(width 0.1)
				(type default)
			)
			(layer "B.Fab")
		)
		(fp_line
			(start 0.12065 -0.2794)
			(end -0.12065 -0.2794)
			(stroke
				(width 0.1)
				(type default)
			)
			(layer "B.Fab")
		)
		(fp_line
			(start -0.67945 -0.3048)
			(end -0.67945 0.3048)
			(stroke
				(width 0.1)
				(type default)
			)
			(layer "B.Fab")
		)
		(fp_line
			(start -0.12065 -0.3048)
			(end -0.67945 -0.3048)
			(stroke
				(width 0.1)
				(type default)
			)
			(layer "B.Fab")
		)
		(fp_line
			(start 0.12065 -0.305054)
			(end 0.12065 -0.2794)
			(stroke
				(width 0.1)
				(type default)
			)
			(layer "B.Fab")
		)
		(fp_line
			(start 0.67945 -0.305054)
			(end 0.12065 -0.305054)
			(stroke
				(width 0.1)
				(type default)
			)
			(layer "B.Fab")
		)
		(pad "1" smd circle
			(at 0.40005 0 90)
			(size 0 0)
			(layers "B.Cu" "B.Mask" "B.Paste")
			(net "P0V8_SERDES_VDDA_PEX3")
		)
		(pad "2" smd circle
			(at -0.40005 0 90)
			(size 0 0)
			(layers "B.Cu" "B.Mask" "B.Paste")
			(net "P0V8_SERDES_VDDA_PEX3_C0")
		)
	)
	(footprint ""
		(layer "B.Cu")
		(at 255.960626 -242.524788 90)
		(property "Reference" "R6577"
			(at 0 0 90)
			(layer "B.SilkS")
			(hide yes)
			(effects
				(font
					(size 1.27 1.27)
				)
				(justify mirror)
			)
		)
		(property "Value" ""
			(at 0 0 90)
			(layer "B.Fab")
			(effects
				(font
					(size 1.27 1.27)
				)
				(justify mirror)
			)
		)
		(duplicate_pad_numbers_are_jumpers no)
		(fp_line
			(start 0.7874 -0.4064)
			(end -0.7874 -0.4064)
			(stroke
				(width 0.1524)
				(type default)
			)
			(layer "B.SilkS")
		)
		(fp_line
			(start -0.7874 -0.4064)
			(end -0.7874 0.4064)
			(stroke
				(width 0.1524)
				(type default)
			)
			(layer "B.SilkS")
		)
		(fp_line
			(start 0.7874 0.4064)
			(end 0.7874 -0.4064)
			(stroke
				(width 0.1524)
				(type default)
			)
			(layer "B.SilkS")
		)
		(fp_line
			(start -0.7874 0.4064)
			(end 0.7874 0.4064)
			(stroke
				(width 0.1524)
				(type default)
			)
			(layer "B.SilkS")
		)
		(fp_line
			(start 0.67945 -0.305054)
			(end 0.12065 -0.305054)
			(stroke
				(width 0.1)
				(type default)
			)
			(layer "B.Fab")
		)
		(fp_line
			(start 0.12065 -0.305054)
			(end 0.12065 -0.2794)
			(stroke
				(width 0.1)
				(type default)
			)
			(layer "B.Fab")
		)
		(fp_line
			(start -0.12065 -0.3048)
			(end -0.67945 -0.3048)
			(stroke
				(width 0.1)
				(type default)
			)
			(layer "B.Fab")
		)
		(fp_line
			(start -0.67945 -0.3048)
			(end -0.67945 0.3048)
			(stroke
				(width 0.1)
				(type default)
			)
			(layer "B.Fab")
		)
		(fp_line
			(start 0.12065 -0.2794)
			(end -0.12065 -0.2794)
			(stroke
				(width 0.1)
				(type default)
			)
			(layer "B.Fab")
		)
		(fp_line
			(start -0.12065 -0.2794)
			(end -0.12065 -0.3048)
			(stroke
				(width 0.1)
				(type default)
			)
			(layer "B.Fab")
		)
		(fp_line
			(start 0.12065 0.2794)
			(end 0.12065 0.3048)
			(stroke
				(width 0.1)
				(type default)
			)
			(layer "B.Fab")
		)
		(fp_line
			(start -0.120396 0.2794)
			(end 0.12065 0.2794)
			(stroke
				(width 0.1)
				(type default)
			)
			(layer "B.Fab")
		)
		(fp_line
			(start 0.67945 0.3048)
			(end 0.67945 -0.305054)
			(stroke
				(width 0.1)
				(type default)
			)
			(layer "B.Fab")
		)
		(fp_line
			(start 0.12065 0.3048)
			(end 0.67945 0.3048)
			(stroke
				(width 0.1)
				(type default)
			)
			(layer "B.Fab")
		)
		(fp_line
			(start -0.120396 0.3048)
			(end -0.120396 0.2794)
			(stroke
				(width 0.1)
				(type default)
			)
			(layer "B.Fab")
		)
		(fp_line
			(start -0.67945 0.3048)
			(end -0.120396 0.3048)
			(stroke
				(width 0.1)
				(type default)
			)
			(layer "B.Fab")
		)
		(pad "1" smd circle
			(at 0.40005 0 270)
			(size 0 0)
			(layers "B.Cu" "B.Mask" "B.Paste")
			(net "P3V3_AUX")
		)
		(pad "2" smd circle
			(at -0.40005 0 270)
			(size 0 0)
			(layers "B.Cu" "B.Mask" "B.Paste")
			(net "PEX2_P1V8_PLL_EN")
		)
	)
	(footprint ""
		(layer "B.Cu")
		(at 234.732322 -90.523314 -90)
		(property "Reference" "C2620"
			(at 0 0 90)
			(layer "B.SilkS")
			(hide yes)
			(effects
				(font
					(size 1.27 1.27)
				)
				(justify mirror)
			)
		)
		(property "Value" ""
			(at 0 0 90)
			(layer "B.Fab")
			(effects
				(font
					(size 1.27 1.27)
				)
				(justify mirror)
			)
		)
		(duplicate_pad_numbers_are_jumpers no)
		(fp_line
			(start -0.7874 0.4064)
			(end 0.7874 0.4064)
			(stroke
				(width 0.1524)
				(type default)
			)
			(layer "B.SilkS")
		)
		(fp_line
			(start 0.7874 0.4064)
			(end 0.7874 -0.4064)
			(stroke
				(width 0.1524)
				(type default)
			)
			(layer "B.SilkS")
		)
		(fp_line
			(start -0.7874 -0.4064)
			(end -0.7874 0.4064)
			(stroke
				(width 0.1524)
				(type default)
			)
			(layer "B.SilkS")
		)
		(fp_line
			(start 0.7874 -0.4064)
			(end -0.7874 -0.4064)
			(stroke
				(width 0.1524)
				(type default)
			)
			(layer "B.SilkS")
		)
		(fp_line
			(start -0.67945 0.3048)
			(end -0.120396 0.3048)
			(stroke
				(width 0.1)
				(type default)
			)
			(layer "B.Fab")
		)
		(fp_line
			(start -0.120396 0.3048)
			(end -0.120396 0.2794)
			(stroke
				(width 0.1)
				(type default)
			)
			(layer "B.Fab")
		)
		(fp_line
			(start 0.12065 0.3048)
			(end 0.67945 0.3048)
			(stroke
				(width 0.1)
				(type default)
			)
			(layer "B.Fab")
		)
		(fp_line
			(start 0.67945 0.3048)
			(end 0.67945 -0.305054)
			(stroke
				(width 0.1)
				(type default)
			)
			(layer "B.Fab")
		)
		(fp_line
			(start -0.120396 0.2794)
			(end 0.12065 0.2794)
			(stroke
				(width 0.1)
				(type default)
			)
			(layer "B.Fab")
		)
		(fp_line
			(start 0.12065 0.2794)
			(end 0.12065 0.3048)
			(stroke
				(width 0.1)
				(type default)
			)
			(layer "B.Fab")
		)
		(fp_line
			(start -0.12065 -0.2794)
			(end -0.12065 -0.3048)
			(stroke
				(width 0.1)
				(type default)
			)
			(layer "B.Fab")
		)
		(fp_line
			(start 0.12065 -0.2794)
			(end -0.12065 -0.2794)
			(stroke
				(width 0.1)
				(type default)
			)
			(layer "B.Fab")
		)
		(fp_line
			(start -0.67945 -0.3048)
			(end -0.67945 0.3048)
			(stroke
				(width 0.1)
				(type default)
			)
			(layer "B.Fab")
		)
		(fp_line
			(start -0.12065 -0.3048)
			(end -0.67945 -0.3048)
			(stroke
				(width 0.1)
				(type default)
			)
			(layer "B.Fab")
		)
		(fp_line
			(start 0.12065 -0.305054)
			(end 0.12065 -0.2794)
			(stroke
				(width 0.1)
				(type default)
			)
			(layer "B.Fab")
		)
		(fp_line
			(start 0.67945 -0.305054)
			(end 0.12065 -0.305054)
			(stroke
				(width 0.1)
				(type default)
			)
			(layer "B.Fab")
		)
		(pad "1" smd circle
			(at 0.40005 0 90)
			(size 0 0)
			(layers "B.Cu" "B.Mask" "B.Paste")
			(net "P3V3_PEX_USB_HUB")
		)
		(pad "2" smd circle
			(at -0.40005 0 90)
			(size 0 0)
			(layers "B.Cu" "B.Mask" "B.Paste")
			(net "GND")
		)
	)
)
